# S9S_MB_2U (Grand Teton) — schematic netlist excerpt (pin names and nets, part order shuffled) for the footprints in the layout excerpt that follows; sources: Cadence DE-HDL packaged netlist, KiCad conversion of 03242023_DA0F0TMBIJ0_F0T_Motherboard_J_brd_V01_OCP.brd

C23  Q_CAP  2.2UF 6.3V 20% X6S  pkg C0402  page 89 : A = P3V3_AUX ; B = GND
R19  Q_RES  499 1% CHIP  pkg 0402LF  page 16 : A = PVNN_TERM_CPU0 ; B = DBP_CPU_MBP1_GTL_N
PC571  Q_CAP  22UF 16V 20% X6S  pkg C0805  page 259 : A = SW_P3V3_AUX_FLT ; B = GND

(kicad_pcb
	(version 20260206)
	(generator "pcbnew")
	(generator_version "10.0")
	(general
		(thickness 1.6)
		(legacy_teardrops no)
	)
	(paper "A4")
	(title_block
		(title "03242023_DA0F0TMBIJ0_F0T_Motherboard_J_brd_V01_OCP.brd")
		(comment 1 "Grand Teton / footprints 5828-5830 of 6105")
	)
	(layers
		(0 "F.Cu" signal "TOP")
		(4 "In1.Cu" signal "GND")
		(6 "In2.Cu" signal "IN1")
		(8 "In3.Cu" signal "GND1")
		(10 "In4.Cu" signal "IN2")
		(12 "In5.Cu" signal "GND2")
		(14 "In6.Cu" signal "IN3")
		(16 "In7.Cu" signal "GND3")
		(18 "In8.Cu" signal "VCC")
		(20 "In9.Cu" signal "VCC1")
		(22 "In10.Cu" signal "GND4")
		(24 "In11.Cu" signal "IN4")
		(26 "In12.Cu" signal "GND5")
		(28 "In13.Cu" signal "IN5")
		(30 "In14.Cu" signal "GND6")
		(32 "In15.Cu" signal "IN6")
		(34 "In16.Cu" signal "GND7")
		(2 "B.Cu" signal "BOTTOM")
		(9 "F.Adhes" user "F.Adhesive")
		(11 "B.Adhes" user "B.Adhesive")
		(13 "F.Paste" user "Package Geometry/Pastemask Top")
		(15 "B.Paste" user "Package Geometry/Pastemask Bottom")
		(5 "F.SilkS" user "Ref Des/Silkscreen Top")
		(7 "B.SilkS" user "Ref Des/Silkscreen Bottom")
		(1 "F.Mask" user "Board Geometry/Soldermask Top")
		(3 "B.Mask" user "Board Geometry/Soldermask Bottom")
		(17 "Dwgs.User" user "User.Drawings")
		(19 "Cmts.User" user "User.Comments")
		(21 "Eco1.User" user "User.Eco1")
		(23 "Eco2.User" user "User.Eco2")
		(25 "Edge.Cuts" user "Board Geometry/Outline")
		(27 "Margin" user)
		(31 "F.CrtYd" user "Package Geometry/Place Bound Top")
		(29 "B.CrtYd" user "Package Geometry/Place Bound Bottom")
		(35 "F.Fab" user "Ref Des/Assembly Top")
		(33 "B.Fab" user "Ref Des/Assembly Bottom")
	)
	(footprint ""
		(layer "B.Cu")
		(at 455.1299 -71.247508 90)
		(property "Reference" "PC571"
			(at 0 0 90)
			(layer "B.SilkS")
			(hide yes)
			(effects
				(font
					(size 1.27 1.27)
				)
				(justify mirror)
			)
		)
		(property "Value" ""
			(at 0 0 90)
			(layer "B.Fab")
			(effects
				(font
					(size 1.27 1.27)
				)
				(justify mirror)
			)
		)
		(duplicate_pad_numbers_are_jumpers no)
		(fp_line
			(start 1.524 -0.762)
			(end -1.524 -0.762)
			(stroke
				(width 0.1524)
				(type default)
			)
			(layer "B.SilkS")
		)
		(fp_line
			(start -1.524 -0.762)
			(end -1.524 0.762)
			(stroke
				(width 0.1524)
				(type default)
			)
			(layer "B.SilkS")
		)
		(fp_line
			(start 1.524 0.762)
			(end 1.524 -0.762)
			(stroke
				(width 0.1524)
				(type default)
			)
			(layer "B.SilkS")
		)
		(fp_line
			(start -1.524 0.762)
			(end 1.524 0.762)
			(stroke
				(width 0.1524)
				(type default)
			)
			(layer "B.SilkS")
		)
		(fp_line
			(start 1.1049 -0.724916)
			(end 1.1049 0.724916)
			(stroke
				(width 0.1)
				(type default)
			)
			(layer "B.Fab")
		)
		(fp_line
			(start -1.1049 -0.724916)
			(end 1.1049 -0.724916)
			(stroke
				(width 0.1)
				(type default)
			)
			(layer "B.Fab")
		)
		(fp_line
			(start 1.1049 0.724916)
			(end -1.1049 0.724916)
			(stroke
				(width 0.1)
				(type default)
			)
			(layer "B.Fab")
		)
		(fp_line
			(start -1.1049 0.724916)
			(end -1.1049 -0.724916)
			(stroke
				(width 0.1)
				(type default)
			)
			(layer "B.Fab")
		)
		(pad "1" smd rect
			(at 0.889 0 90)
			(size 1.016 1.27)
			(layers "B.Cu" "B.Mask" "B.Paste")
			(net "SW_P3V3_AUX_FLT")
		)
		(pad "2" smd rect
			(at -0.889 0 90)
			(size 1.016 1.27)
			(layers "B.Cu" "B.Mask" "B.Paste")
			(net "GND")
		)
	)
	(footprint ""
		(layer "B.Cu")
		(at 334.662018 -188.92647 -90)
		(property "Reference" "R19"
			(at 0 0 90)
			(layer "B.SilkS")
			(hide yes)
			(effects
				(font
					(size 1.27 1.27)
				)
				(justify mirror)
			)
		)
		(property "Value" ""
			(at 0 0 90)
			(layer "B.Fab")
			(effects
				(font
					(size 1.27 1.27)
				)
				(justify mirror)
			)
		)
		(duplicate_pad_numbers_are_jumpers no)
		(fp_line
			(start -0.7874 0.4064)
			(end 0.7874 0.4064)
			(stroke
				(width 0.1524)
				(type default)
			)
			(layer "B.SilkS")
		)
		(fp_line
			(start 0.7874 0.4064)
			(end 0.7874 -0.4064)
			(stroke
				(width 0.1524)
				(type default)
			)
			(layer "B.SilkS")
		)
		(fp_line
			(start -0.7874 -0.4064)
			(end -0.7874 0.4064)
			(stroke
				(width 0.1524)
				(type default)
			)
			(layer "B.SilkS")
		)
		(fp_line
			(start 0.7874 -0.4064)
			(end -0.7874 -0.4064)
			(stroke
				(width 0.1524)
				(type default)
			)
			(layer "B.SilkS")
		)
		(fp_line
			(start -0.67945 0.3048)
			(end -0.120396 0.3048)
			(stroke
				(width 0.1)
				(type default)
			)
			(layer "B.Fab")
		)
		(fp_line
			(start -0.120396 0.3048)
			(end -0.120396 0.2794)
			(stroke
				(width 0.1)
				(type default)
			)
			(layer "B.Fab")
		)
		(fp_line
			(start 0.12065 0.3048)
			(end 0.67945 0.3048)
			(stroke
				(width 0.1)
				(type default)
			)
			(layer "B.Fab")
		)
		(fp_line
			(start 0.67945 0.3048)
			(end 0.67945 -0.305054)
			(stroke
				(width 0.1)
				(type default)
			)
			(layer "B.Fab")
		)
		(fp_line
			(start -0.120396 0.2794)
			(end 0.12065 0.2794)
			(stroke
				(width 0.1)
				(type default)
			)
			(layer "B.Fab")
		)
		(fp_line
			(start 0.12065 0.2794)
			(end 0.12065 0.3048)
			(stroke
				(width 0.1)
				(type default)
			)
			(layer "B.Fab")
		)
		(fp_line
			(start -0.12065 -0.2794)
			(end -0.12065 -0.3048)
			(stroke
				(width 0.1)
				(type default)
			)
			(layer "B.Fab")
		)
		(fp_line
			(start 0.12065 -0.2794)
			(end -0.12065 -0.2794)
			(stroke
				(width 0.1)
				(type default)
			)
			(layer "B.Fab")
		)
		(fp_line
			(start -0.67945 -0.3048)
			(end -0.67945 0.3048)
			(stroke
				(width 0.1)
				(type default)
			)
			(layer "B.Fab")
		)
		(fp_line
			(start -0.12065 -0.3048)
			(end -0.67945 -0.3048)
			(stroke
				(width 0.1)
				(type default)
			)
			(layer "B.Fab")
		)
		(fp_line
			(start 0.12065 -0.305054)
			(end 0.12065 -0.2794)
			(stroke
				(width 0.1)
				(type default)
			)
			(layer "B.Fab")
		)
		(fp_line
			(start 0.67945 -0.305054)
			(end 0.12065 -0.305054)
			(stroke
				(width 0.1)
				(type default)
			)
			(layer "B.Fab")
		)
		(pad "1" smd circle
			(at 0.40005 0 90)
			(size 0 0)
			(layers "B.Cu" "B.Mask" "B.Paste")
			(net "PVNN_TERM_CPU0")
		)
		(pad "2" smd circle
			(at -0.40005 0 90)
			(size 0 0)
			(layers "B.Cu" "B.Mask" "B.Paste")
			(net "DBP_CPU_MBP1_GTL_N")
		)
	)
	(footprint ""
		(layer "B.Cu")
		(at 263.637014 -319.263776 180)
		(property "Reference" "C23"
			(at 0 0 0)
			(layer "B.SilkS")
			(hide yes)
			(effects
				(font
					(size 1.27 1.27)
				)
				(justify mirror)
			)
		)
		(property "Value" ""
			(at 0 0 0)
			(layer "B.Fab")
			(effects
				(font
					(size 1.27 1.27)
				)
				(justify mirror)
			)
		)
		(duplicate_pad_numbers_are_jumpers no)
		(fp_line
			(start 0.7874 0.4064)
			(end 0.7874 -0.4064)
			(stroke
				(width 0.1524)
				(type default)
			)
			(layer "B.SilkS")
		)
		(fp_line
			(start 0.7874 -0.4064)
			(end -0.7874 -0.4064)
			(stroke
				(width 0.1524)
				(type default)
			)
			(layer "B.SilkS")
		)
		(fp_line
			(start -0.7874 0.4064)
			(end 0.7874 0.4064)
			(stroke
				(width 0.1524)
				(type default)
			)
			(layer "B.SilkS")
		)
		(fp_line
			(start -0.7874 -0.4064)
			(end -0.7874 0.4064)
			(stroke
				(width 0.1524)
				(type default)
			)
			(layer "B.SilkS")
		)
		(fp_line
			(start 0.67945 0.3048)
			(end 0.67945 -0.305054)
			(stroke
				(width 0.1)
				(type default)
			)
			(layer "B.Fab")
		)
		(fp_line
			(start 0.67945 -0.305054)
			(end 0.12065 -0.305054)
			(stroke
				(width 0.1)
				(type default)
			)
			(layer "B.Fab")
		)
		(fp_line
			(start 0.12065 0.3048)
			(end 0.67945 0.3048)
			(stroke
				(width 0.1)
				(type default)
			)
			(layer "B.Fab")
		)
		(fp_line
			(start 0.12065 0.2794)
			(end 0.12065 0.3048)
			(stroke
				(width 0.1)
				(type default)
			)
			(layer "B.Fab")
		)
		(fp_line
			(start 0.12065 -0.2794)
			(end -0.12065 -0.2794)
			(stroke
				(width 0.1)
				(type default)
			)
			(layer "B.Fab")
		)
		(fp_line
			(start 0.12065 -0.305054)
			(end 0.12065 -0.2794)
			(stroke
				(width 0.1)
				(type default)
			)
			(layer "B.Fab")
		)
		(fp_line
			(start -0.120396 0.3048)
			(end -0.120396 0.2794)
			(stroke
				(width 0.1)
				(type default)
			)
			(layer "B.Fab")
		)
		(fp_line
			(start -0.120396 0.2794)
			(end 0.12065 0.2794)
			(stroke
				(width 0.1)
				(type default)
			)
			(layer "B.Fab")
		)
		(fp_line
			(start -0.12065 -0.2794)
			(end -0.12065 -0.3048)
			(stroke
				(width 0.1)
				(type default)
			)
			(layer "B.Fab")
		)
		(fp_line
			(start -0.12065 -0.3048)
			(end -0.67945 -0.3048)
			(stroke
				(width 0.1)
				(type default)
			)
			(layer "B.Fab")
		)
		(fp_line
			(start -0.67945 0.3048)
			(end -0.120396 0.3048)
			(stroke
				(width 0.1)
				(type default)
			)
			(layer "B.Fab")
		)
		(fp_line
			(start -0.67945 -0.3048)
			(end -0.67945 0.3048)
			(stroke
				(width 0.1)
				(type default)
			)
			(layer "B.Fab")
		)
		(pad "1" smd circle
			(at 0.40005 0)
			(size 0 0)
			(layers "B.Cu" "B.Mask" "B.Paste")
			(net "P3V3_AUX")
		)
		(pad "2" smd circle
			(at -0.40005 0)
			(size 0 0)
			(layers "B.Cu" "B.Mask" "B.Paste")
			(net "GND")
		)
	)
)
